# S9S_MB_2U (Grand Teton) — schematic netlist excerpt (pin names and nets, part order shuffled) for the footprints in the layout excerpt that follows; sources: Cadence DE-HDL packaged netlist, KiCad conversion of 03242023_DA0F0TMBIJ0_F0T_Motherboard_J_brd_V01_OCP.brd

R3462  Q_RES  100K 1% EMPTY  pkg 0402LF  page 150 : A = GPU_NVS_PWR_BRAKE_N_R ; B = GND
PC629  Q_CAP  100NF 50V 10% EMPTY  pkg C0402  page 278 : A = PVCCD_HV_CPU0_VCC ; B = GND

(kicad_pcb
	(version 20260206)
	(generator "pcbnew")
	(generator_version "10.0")
	(general
		(thickness 1.6)
		(legacy_teardrops no)
	)
	(paper "A4")
	(title_block
		(title "03242023_DA0F0TMBIJ0_F0T_Motherboard_J_brd_V01_OCP.brd")
		(comment 1 "Grand Teton / footprints 658-659 of 6105")
	)
	(layers
		(0 "F.Cu" signal "TOP")
		(4 "In1.Cu" signal "GND")
		(6 "In2.Cu" signal "IN1")
		(8 "In3.Cu" signal "GND1")
		(10 "In4.Cu" signal "IN2")
		(12 "In5.Cu" signal "GND2")
		(14 "In6.Cu" signal "IN3")
		(16 "In7.Cu" signal "GND3")
		(18 "In8.Cu" signal "VCC")
		(20 "In9.Cu" signal "VCC1")
		(22 "In10.Cu" signal "GND4")
		(24 "In11.Cu" signal "IN4")
		(26 "In12.Cu" signal "GND5")
		(28 "In13.Cu" signal "IN5")
		(30 "In14.Cu" signal "GND6")
		(32 "In15.Cu" signal "IN6")
		(34 "In16.Cu" signal "GND7")
		(2 "B.Cu" signal "BOTTOM")
		(9 "F.Adhes" user "F.Adhesive")
		(11 "B.Adhes" user "B.Adhesive")
		(13 "F.Paste" user "Package Geometry/Pastemask Top")
		(15 "B.Paste" user "Package Geometry/Pastemask Bottom")
		(5 "F.SilkS" user "Ref Des/Silkscreen Top")
		(7 "B.SilkS" user "Ref Des/Silkscreen Bottom")
		(1 "F.Mask" user "Board Geometry/Soldermask Top")
		(3 "B.Mask" user "Board Geometry/Soldermask Bottom")
		(17 "Dwgs.User" user "User.Drawings")
		(19 "Cmts.User" user "User.Comments")
		(21 "Eco1.User" user "User.Eco1")
		(23 "Eco2.User" user "User.Eco2")
		(25 "Edge.Cuts" user "Board Geometry/Outline")
		(27 "Margin" user)
		(31 "F.CrtYd" user "Package Geometry/Place Bound Top")
		(29 "B.CrtYd" user "Package Geometry/Place Bound Bottom")
		(35 "F.Fab" user "Ref Des/Assembly Top")
		(33 "B.Fab" user "Ref Des/Assembly Bottom")
	)
	(footprint ""
		(layer "F.Cu")
		(at 428.62373 -120.365012 180)
		(property "Reference" "PC629"
			(at 0 0 180)
			(layer "F.SilkS")
			(hide yes)
			(effects
				(font
					(size 1.27 1.27)
				)
			)
		)
		(property "Value" ""
			(at 0 0 180)
			(layer "F.Fab")
			(effects
				(font
					(size 1.27 1.27)
				)
			)
		)
		(duplicate_pad_numbers_are_jumpers no)
		(fp_line
			(start 0.7874 0.4064)
			(end -0.7874 0.4064)
			(stroke
				(width 0.1524)
				(type default)
			)
			(layer "F.SilkS")
		)
		(fp_line
			(start 0.7874 -0.4064)
			(end 0.7874 0.4064)
			(stroke
				(width 0.1524)
				(type default)
			)
			(layer "F.SilkS")
		)
		(fp_line
			(start -0.7874 0.4064)
			(end -0.7874 -0.4064)
			(stroke
				(width 0.1524)
				(type default)
			)
			(layer "F.SilkS")
		)
		(fp_line
			(start -0.7874 -0.4064)
			(end 0.7874 -0.4064)
			(stroke
				(width 0.1524)
				(type default)
			)
			(layer "F.SilkS")
		)
		(fp_line
			(start 0.67945 0.3048)
			(end 0.120396 0.3048)
			(stroke
				(width 0.1)
				(type default)
			)
			(layer "F.Fab")
		)
		(fp_line
			(start 0.67945 -0.3048)
			(end 0.67945 0.3048)
			(stroke
				(width 0.1)
				(type default)
			)
			(layer "F.Fab")
		)
		(fp_line
			(start 0.12065 -0.2794)
			(end 0.12065 -0.3048)
			(stroke
				(width 0.1)
				(type default)
			)
			(layer "F.Fab")
		)
		(fp_line
			(start 0.12065 -0.3048)
			(end 0.67945 -0.3048)
			(stroke
				(width 0.1)
				(type default)
			)
			(layer "F.Fab")
		)
		(fp_line
			(start 0.120396 0.3048)
			(end 0.120396 0.2794)
			(stroke
				(width 0.1)
				(type default)
			)
			(layer "F.Fab")
		)
		(fp_line
			(start 0.120396 0.2794)
			(end -0.12065 0.2794)
			(stroke
				(width 0.1)
				(type default)
			)
			(layer "F.Fab")
		)
		(fp_line
			(start -0.12065 0.3048)
			(end -0.67945 0.3048)
			(stroke
				(width 0.1)
				(type default)
			)
			(layer "F.Fab")
		)
		(fp_line
			(start -0.12065 0.2794)
			(end -0.12065 0.3048)
			(stroke
				(width 0.1)
				(type default)
			)
			(layer "F.Fab")
		)
		(fp_line
			(start -0.12065 -0.2794)
			(end 0.12065 -0.2794)
			(stroke
				(width 0.1)
				(type default)
			)
			(layer "F.Fab")
		)
		(fp_line
			(start -0.12065 -0.305054)
			(end -0.12065 -0.2794)
			(stroke
				(width 0.1)
				(type default)
			)
			(layer "F.Fab")
		)
		(fp_line
			(start -0.67945 0.3048)
			(end -0.67945 -0.305054)
			(stroke
				(width 0.1)
				(type default)
			)
			(layer "F.Fab")
		)
		(fp_line
			(start -0.67945 -0.305054)
			(end -0.12065 -0.305054)
			(stroke
				(width 0.1)
				(type default)
			)
			(layer "F.Fab")
		)
		(pad "1" smd circle
			(at -0.40005 0 180)
			(size 0 0)
			(layers "F.Cu" "F.Mask" "F.Paste")
			(net "PVCCD_HV_CPU0_VCC")
		)
		(pad "2" smd circle
			(at 0.40005 0 180)
			(size 0 0)
			(layers "F.Cu" "F.Mask" "F.Paste")
			(net "GND")
		)
	)
	(footprint ""
		(layer "F.Cu")
		(at 101.833934 -392.63574 180)
		(property "Reference" "R3462"
			(at 0 0 180)
			(layer "F.SilkS")
			(hide yes)
			(effects
				(font
					(size 1.27 1.27)
				)
			)
		)
		(property "Value" ""
			(at 0 0 180)
			(layer "F.Fab")
			(effects
				(font
					(size 1.27 1.27)
				)
			)
		)
		(duplicate_pad_numbers_are_jumpers no)
		(fp_line
			(start 0.7874 0.4064)
			(end -0.7874 0.4064)
			(stroke
				(width 0.1524)
				(type default)
			)
			(layer "F.SilkS")
		)
		(fp_line
			(start 0.7874 -0.4064)
			(end 0.7874 0.4064)
			(stroke
				(width 0.1524)
				(type default)
			)
			(layer "F.SilkS")
		)
		(fp_line
			(start -0.7874 0.4064)
			(end -0.7874 -0.4064)
			(stroke
				(width 0.1524)
				(type default)
			)
			(layer "F.SilkS")
		)
		(fp_line
			(start -0.7874 -0.4064)
			(end 0.7874 -0.4064)
			(stroke
				(width 0.1524)
				(type default)
			)
			(layer "F.SilkS")
		)
		(fp_line
			(start 0.67945 0.3048)
			(end 0.120396 0.3048)
			(stroke
				(width 0.1)
				(type default)
			)
			(layer "F.Fab")
		)
		(fp_line
			(start 0.67945 -0.3048)
			(end 0.67945 0.3048)
			(stroke
				(width 0.1)
				(type default)
			)
			(layer "F.Fab")
		)
		(fp_line
			(start 0.12065 -0.2794)
			(end 0.12065 -0.3048)
			(stroke
				(width 0.1)
				(type default)
			)
			(layer "F.Fab")
		)
		(fp_line
			(start 0.12065 -0.3048)
			(end 0.67945 -0.3048)
			(stroke
				(width 0.1)
				(type default)
			)
			(layer "F.Fab")
		)
		(fp_line
			(start 0.120396 0.3048)
			(end 0.120396 0.2794)
			(stroke
				(width 0.1)
				(type default)
			)
			(layer "F.Fab")
		)
		(fp_line
			(start 0.120396 0.2794)
			(end -0.12065 0.2794)
			(stroke
				(width 0.1)
				(type default)
			)
			(layer "F.Fab")
		)
		(fp_line
			(start -0.12065 0.3048)
			(end -0.67945 0.3048)
			(stroke
				(width 0.1)
				(type default)
			)
			(layer "F.Fab")
		)
		(fp_line
			(start -0.12065 0.2794)
			(end -0.12065 0.3048)
			(stroke
				(width 0.1)
				(type default)
			)
			(layer "F.Fab")
		)
		(fp_line
			(start -0.12065 -0.2794)
			(end 0.12065 -0.2794)
			(stroke
				(width 0.1)
				(type default)
			)
			(layer "F.Fab")
		)
		(fp_line
			(start -0.12065 -0.305054)
			(end -0.12065 -0.2794)
			(stroke
				(width 0.1)
				(type default)
			)
			(layer "F.Fab")
		)
		(fp_line
			(start -0.67945 0.3048)
			(end -0.67945 -0.305054)
			(stroke
				(width 0.1)
				(type default)
			)
			(layer "F.Fab")
		)
		(fp_line
			(start -0.67945 -0.305054)
			(end -0.12065 -0.305054)
			(stroke
				(width 0.1)
				(type default)
			)
			(layer "F.Fab")
		)
		(pad "1" smd circle
			(at -0.40005 0 180)
			(size 0 0)
			(layers "F.Cu" "F.Mask" "F.Paste")
			(net "GPU_NVS_PWR_BRAKE_N_R")
		)
		(pad "2" smd circle
			(at 0.40005 0 180)
			(size 0 0)
			(layers "F.Cu" "F.Mask" "F.Paste")
			(net "GND")
		)
	)
)
